# S9S_MB_2U (Grand Teton) — schematic netlist excerpt (pin names and nets, part order shuffled) for the footprints in the layout excerpt that follows; sources: Cadence DE-HDL packaged netlist, KiCad conversion of 03242023_DA0F0TMBIJ0_F0T_Motherboard_J_brd_V01_OCP.brd

PU299  RS31312R  IC  pkg QFN22_TH_3X5  page 242
  EN  = P12V_SCM_EN_R2
  LOADEN  = GND
  ENTM  = GND
  TIMER  = P12V_SCM_TIMER
  ISET  = P12V_SCM_ISET
  SS  = P12V_SCM_SS
  GND  = GND
  IMON  = P12V_SCM_IMON
  FLTB  = P12V_SCM_FLTB_N
  PG  = HP_LVC3_SCM_HSC_PWRGD_R
  OV  = P12V_SCM_OV_FB
  AVIN  = P12V_SCM_AVIN_PD
  VOUT_13  = P12V_SCM_R
  VOUT_14  = P12V_SCM_R
  VOUT_15  = P12V_SCM_R
  VOUT_16  = P12V_SCM_R
  VOUT_17  = P12V_SCM_R
  VOUT_18  = P12V_SCM_R
  VOUT_19  = P12V_SCM_R
  VOUT_20  = P12V_SCM_R
  VIN_21_22  = P12V_AUX
  VIN_23  = P12V_AUX
  VIN_24  = P12V_AUX
  VIN_25  = P12V_AUX
  VIN_26  = P12V_AUX

(kicad_pcb
	(version 20260206)
	(generator "pcbnew")
	(generator_version "10.0")
	(general
		(thickness 1.6)
		(legacy_teardrops no)
	)
	(paper "A4")
	(title_block
		(title "03242023_DA0F0TMBIJ0_F0T_Motherboard_J_brd_V01_OCP.brd")
		(comment 1 "Grand Teton / footprint 3750 of 6105 (PU299), pads 1-25 of 25")
	)
	(layers
		(0 "F.Cu" signal "TOP")
		(4 "In1.Cu" signal "GND")
		(6 "In2.Cu" signal "IN1")
		(8 "In3.Cu" signal "GND1")
		(10 "In4.Cu" signal "IN2")
		(12 "In5.Cu" signal "GND2")
		(14 "In6.Cu" signal "IN3")
		(16 "In7.Cu" signal "GND3")
		(18 "In8.Cu" signal "VCC")
		(20 "In9.Cu" signal "VCC1")
		(22 "In10.Cu" signal "GND4")
		(24 "In11.Cu" signal "IN4")
		(26 "In12.Cu" signal "GND5")
		(28 "In13.Cu" signal "IN5")
		(30 "In14.Cu" signal "GND6")
		(32 "In15.Cu" signal "IN6")
		(34 "In16.Cu" signal "GND7")
		(2 "B.Cu" signal "BOTTOM")
		(9 "F.Adhes" user "F.Adhesive")
		(11 "B.Adhes" user "B.Adhesive")
		(13 "F.Paste" user "Package Geometry/Pastemask Top")
		(15 "B.Paste" user "Package Geometry/Pastemask Bottom")
		(5 "F.SilkS" user "Ref Des/Silkscreen Top")
		(7 "B.SilkS" user "Ref Des/Silkscreen Bottom")
		(1 "F.Mask" user "Board Geometry/Soldermask Top")
		(3 "B.Mask" user "Board Geometry/Soldermask Bottom")
		(17 "Dwgs.User" user "User.Drawings")
		(19 "Cmts.User" user "User.Comments")
		(21 "Eco1.User" user "User.Eco1")
		(23 "Eco2.User" user "User.Eco2")
		(25 "Edge.Cuts" user "Board Geometry/Outline")
		(27 "Margin" user)
		(31 "F.CrtYd" user "Package Geometry/Place Bound Top")
		(29 "B.CrtYd" user "Package Geometry/Place Bound Bottom")
		(35 "F.Fab" user "Ref Des/Assembly Top")
		(33 "B.Fab" user "Ref Des/Assembly Bottom")
	)
	(footprint ""
		(layer "F.Cu")
		(at 177.694082 -28.937712 -90)
		(property "Reference" "PU299"
			(at -3.695446 10.633202 0)
			(unlocked yes)
			(layer "F.SilkS")
			(effects
				(font
					(size 0.7874 0.5842)
					(thickness 0.1524)
				)
				(justify left)
			)
		)
		(property "Value" ""
			(at 0 0 270)
			(layer "F.Fab")
			(effects
				(font
					(size 1.27 1.27)
				)
			)
		)
		(duplicate_pad_numbers_are_jumpers no)
		(pad "1" smd circle
			(at -1.374902 -1.999996 180)
			(size 0 0)
			(layers "F.Cu" "F.Mask" "F.Paste")
			(net "P12V_SCM_EN_R2")
		)
		(pad "2" smd rect
			(at -1.400048 -1.500124 180)
			(size 0.254 0.8128)
			(layers "F.Cu" "F.Mask" "F.Paste")
			(net "GND")
		)
		(pad "3" smd rect
			(at -1.400048 -0.999998 180)
			(size 0.254 0.8128)
			(layers "F.Cu" "F.Mask" "F.Paste")
			(net "GND")
		)
		(pad "4" smd rect
			(at -1.400048 -0.499872 180)
			(size 0.254 0.8128)
			(layers "F.Cu" "F.Mask" "F.Paste")
			(net "P12V_SCM_TIMER")
		)
		(pad "5" smd rect
			(at -1.400048 0 180)
			(size 0.254 0.8128)
			(layers "F.Cu" "F.Mask" "F.Paste")
			(net "P12V_SCM_ISET")
		)
		(pad "6" smd rect
			(at -1.400048 0.499872 180)
			(size 0.254 0.8128)
			(layers "F.Cu" "F.Mask" "F.Paste")
			(net "P12V_SCM_SS")
		)
		(pad "7" smd rect
			(at -1.400048 0.999998 180)
			(size 0.254 0.8128)
			(layers "F.Cu" "F.Mask" "F.Paste")
			(net "GND")
		)
		(pad "8" smd rect
			(at -1.400048 1.500124 180)
			(size 0.254 0.8128)
			(layers "F.Cu" "F.Mask" "F.Paste")
			(net "P12V_SCM_IMON")
		)
		(pad "9" smd rect
			(at -1.400048 1.999996 180)
			(size 0.254 0.8128)
			(layers "F.Cu" "F.Mask" "F.Paste")
			(net "P12V_SCM_FLTB_N")
		)
		(pad "10" smd rect
			(at -0.499872 2.400046 270)
			(size 0.254 0.8128)
			(layers "F.Cu" "F.Mask" "F.Paste")
			(net "HP_LVC3_SCM_HSC_PWRGD_R")
		)
		(pad "11" smd rect
			(at 0.499872 2.400046 270)
			(size 0.254 0.8128)
			(layers "F.Cu" "F.Mask" "F.Paste")
			(net "P12V_SCM_OV_FB")
		)
		(pad "12" smd rect
			(at 1.400048 1.999996 180)
			(size 0.254 0.8128)
			(layers "F.Cu" "F.Mask" "F.Paste")
			(net "P12V_SCM_AVIN_PD")
		)
		(pad "13" smd rect
			(at 1.400048 1.500124 180)
			(size 0.254 0.8128)
			(layers "F.Cu" "F.Mask" "F.Paste")
			(net "P12V_SCM_R")
		)
		(pad "14" smd rect
			(at 1.400048 0.999998 180)
			(size 0.254 0.8128)
			(layers "F.Cu" "F.Mask" "F.Paste")
			(net "P12V_SCM_R")
		)
		(pad "15" smd rect
			(at 1.400048 0.499872 180)
			(size 0.254 0.8128)
			(layers "F.Cu" "F.Mask" "F.Paste")
			(net "P12V_SCM_R")
		)
		(pad "16" smd rect
			(at 1.400048 0 180)
			(size 0.254 0.8128)
			(layers "F.Cu" "F.Mask" "F.Paste")
			(net "P12V_SCM_R")
		)
		(pad "17" smd rect
			(at 1.400048 -0.499872 180)
			(size 0.254 0.8128)
			(layers "F.Cu" "F.Mask" "F.Paste")
			(net "P12V_SCM_R")
		)
		(pad "18" smd rect
			(at 1.400048 -0.999998 180)
			(size 0.254 0.8128)
			(layers "F.Cu" "F.Mask" "F.Paste")
			(net "P12V_SCM_R")
		)
		(pad "19" smd rect
			(at 1.400048 -1.500124 180)
			(size 0.254 0.8128)
			(layers "F.Cu" "F.Mask" "F.Paste")
			(net "P12V_SCM_R")
		)
		(pad "20" smd rect
			(at 1.400048 -1.999996 180)
			(size 0.254 0.8128)
			(layers "F.Cu" "F.Mask" "F.Paste")
			(net "P12V_SCM_R")
		)
		(pad "21_22" smd circle
			(at 0.499872 -2.337562 180)
			(size 0 0)
			(layers "F.Cu" "F.Mask" "F.Paste")
			(net "P12V_AUX")
		)
		(pad "23" smd rect
			(at 0 -1.100074 180)
			(size 0.254 1.27)
			(layers "F.Cu" "F.Mask" "F.Paste")
			(net "P12V_AUX")
		)
		(pad "24" smd rect
			(at 0 -0.199898 180)
			(size 0.254 1.27)
			(layers "F.Cu" "F.Mask" "F.Paste")
			(net "P12V_AUX")
		)
		(pad "25" smd rect
			(at 0 0.700024 180)
			(size 0.254 1.27)
			(layers "F.Cu" "F.Mask" "F.Paste")
			(net "P12V_AUX")
		)
		(pad "26" smd rect
			(at 0 1.599946 180)
			(size 0.254 1.27)
			(layers "F.Cu" "F.Mask" "F.Paste")
			(net "P12V_AUX")
		)
	)
)
